# T6G (Grand Teton) — schematic netlist excerpt (pin names and nets, part order shuffled) for the footprints in the layout excerpt that follows; sources: Cadence DE-HDL packaged netlist, KiCad conversion of 04192023_DAF0TMB3IC0_F0TG_MB_C_brd_V02_OCP.brd

R6850  Q_RES  33 5% CHIP  pkg 0402LF  page 80 : A = P1V8_RETIMER_CPU0_EN ; B = P1V8_RETIMER_CPU0_R_EN
C8069  Q_CAP  1000PF 50V 5% X7R  pkg 0402  page 200 : A = PVDDCR_CPU1_P0_EN_R ; B = GND

(kicad_pcb
	(version 20260206)
	(generator "pcbnew")
	(generator_version "10.0")
	(general
		(thickness 1.6)
		(legacy_teardrops no)
	)
	(paper "A4")
	(title_block
		(title "04192023_DAF0TMB3IC0_F0TG_MB_C_brd_V02_OCP.brd")
		(comment 1 "Grand Teton / footprints 3864-3865 of 8354")
	)
	(layers
		(0 "F.Cu" signal "TOP")
		(4 "In1.Cu" signal "GND")
		(6 "In2.Cu" signal "IN1")
		(8 "In3.Cu" signal "GND1")
		(10 "In4.Cu" signal "IN2")
		(12 "In5.Cu" signal "GND2")
		(14 "In6.Cu" signal "IN3")
		(16 "In7.Cu" signal "GND3")
		(18 "In8.Cu" signal "VCC")
		(20 "In9.Cu" signal "VCC1")
		(22 "In10.Cu" signal "GND4")
		(24 "In11.Cu" signal "IN4")
		(26 "In12.Cu" signal "GND5")
		(28 "In13.Cu" signal "IN5")
		(30 "In14.Cu" signal "GND6")
		(32 "In15.Cu" signal "IN6")
		(34 "In16.Cu" signal "GND7")
		(2 "B.Cu" signal "BOTTOM")
		(9 "F.Adhes" user "F.Adhesive")
		(11 "B.Adhes" user "B.Adhesive")
		(13 "F.Paste" user "Package Geometry/Pastemask Top")
		(15 "B.Paste" user "Package Geometry/Pastemask Bottom")
		(5 "F.SilkS" user "Ref Des/Silkscreen Top")
		(7 "B.SilkS" user "Ref Des/Silkscreen Bottom")
		(1 "F.Mask" user "Board Geometry/Soldermask Top")
		(3 "B.Mask" user "Board Geometry/Soldermask Bottom")
		(17 "Dwgs.User" user "User.Drawings")
		(19 "Cmts.User" user "User.Comments")
		(21 "Eco1.User" user "User.Eco1")
		(23 "Eco2.User" user "User.Eco2")
		(25 "Edge.Cuts" user "Board Geometry/Outline")
		(27 "Margin" user)
		(31 "F.CrtYd" user "Package Geometry/Place Bound Top")
		(29 "B.CrtYd" user "Package Geometry/Place Bound Bottom")
		(35 "F.Fab" user "Ref Des/Assembly Top")
		(33 "B.Fab" user "Ref Des/Assembly Bottom")
	)
	(footprint ""
		(layer "F.Cu")
		(at 304.419 -362.839 180)
		(property "Reference" "C8069"
			(at 0 0 180)
			(layer "F.SilkS")
			(hide yes)
			(effects
				(font
					(size 1.27 1.27)
				)
			)
		)
		(property "Value" ""
			(at 0 0 180)
			(layer "F.Fab")
			(effects
				(font
					(size 1.27 1.27)
				)
			)
		)
		(duplicate_pad_numbers_are_jumpers no)
		(fp_line
			(start 0.7874 0.4064)
			(end -0.7874 0.4064)
			(stroke
				(width 0.1524)
				(type default)
			)
			(layer "F.SilkS")
		)
		(fp_line
			(start 0.7874 -0.4064)
			(end 0.7874 0.4064)
			(stroke
				(width 0.1524)
				(type default)
			)
			(layer "F.SilkS")
		)
		(fp_line
			(start -0.7874 0.4064)
			(end -0.7874 -0.4064)
			(stroke
				(width 0.1524)
				(type default)
			)
			(layer "F.SilkS")
		)
		(fp_line
			(start -0.7874 -0.4064)
			(end 0.7874 -0.4064)
			(stroke
				(width 0.1524)
				(type default)
			)
			(layer "F.SilkS")
		)
		(fp_line
			(start 0.67945 0.3048)
			(end 0.120396 0.3048)
			(stroke
				(width 0.1)
				(type default)
			)
			(layer "F.Fab")
		)
		(fp_line
			(start 0.67945 -0.3048)
			(end 0.67945 0.3048)
			(stroke
				(width 0.1)
				(type default)
			)
			(layer "F.Fab")
		)
		(fp_line
			(start 0.12065 -0.2794)
			(end 0.12065 -0.3048)
			(stroke
				(width 0.1)
				(type default)
			)
			(layer "F.Fab")
		)
		(fp_line
			(start 0.12065 -0.3048)
			(end 0.67945 -0.3048)
			(stroke
				(width 0.1)
				(type default)
			)
			(layer "F.Fab")
		)
		(fp_line
			(start 0.120396 0.3048)
			(end 0.120396 0.2794)
			(stroke
				(width 0.1)
				(type default)
			)
			(layer "F.Fab")
		)
		(fp_line
			(start 0.120396 0.2794)
			(end -0.12065 0.2794)
			(stroke
				(width 0.1)
				(type default)
			)
			(layer "F.Fab")
		)
		(fp_line
			(start -0.12065 0.3048)
			(end -0.67945 0.3048)
			(stroke
				(width 0.1)
				(type default)
			)
			(layer "F.Fab")
		)
		(fp_line
			(start -0.12065 0.2794)
			(end -0.12065 0.3048)
			(stroke
				(width 0.1)
				(type default)
			)
			(layer "F.Fab")
		)
		(fp_line
			(start -0.12065 -0.2794)
			(end 0.12065 -0.2794)
			(stroke
				(width 0.1)
				(type default)
			)
			(layer "F.Fab")
		)
		(fp_line
			(start -0.12065 -0.305054)
			(end -0.12065 -0.2794)
			(stroke
				(width 0.1)
				(type default)
			)
			(layer "F.Fab")
		)
		(fp_line
			(start -0.67945 0.3048)
			(end -0.67945 -0.305054)
			(stroke
				(width 0.1)
				(type default)
			)
			(layer "F.Fab")
		)
		(fp_line
			(start -0.67945 -0.305054)
			(end -0.12065 -0.305054)
			(stroke
				(width 0.1)
				(type default)
			)
			(layer "F.Fab")
		)
		(pad "1" smd circle
			(at -0.40005 0 180)
			(size 0 0)
			(layers "F.Cu" "F.Mask" "F.Paste")
			(net "PVDDCR_CPU1_P0_EN_R")
		)
		(pad "2" smd circle
			(at 0.40005 0 180)
			(size 0 0)
			(layers "F.Cu" "F.Mask" "F.Paste")
			(net "GND")
		)
	)
	(footprint ""
		(layer "F.Cu")
		(at 171.776644 -128.24333)
		(property "Reference" "R6850"
			(at 0 0 0)
			(layer "F.SilkS")
			(hide yes)
			(effects
				(font
					(size 1.27 1.27)
				)
			)
		)
		(property "Value" ""
			(at 0 0 0)
			(layer "F.Fab")
			(effects
				(font
					(size 1.27 1.27)
				)
			)
		)
		(duplicate_pad_numbers_are_jumpers no)
		(fp_line
			(start -0.7874 -0.4064)
			(end 0.7874 -0.4064)
			(stroke
				(width 0.1524)
				(type default)
			)
			(layer "F.SilkS")
		)
		(fp_line
			(start -0.7874 0.4064)
			(end -0.7874 -0.4064)
			(stroke
				(width 0.1524)
				(type default)
			)
			(layer "F.SilkS")
		)
		(fp_line
			(start 0.7874 -0.4064)
			(end 0.7874 0.4064)
			(stroke
				(width 0.1524)
				(type default)
			)
			(layer "F.SilkS")
		)
		(fp_line
			(start 0.7874 0.4064)
			(end -0.7874 0.4064)
			(stroke
				(width 0.1524)
				(type default)
			)
			(layer "F.SilkS")
		)
		(fp_line
			(start -0.67945 -0.305054)
			(end -0.12065 -0.305054)
			(stroke
				(width 0.1)
				(type default)
			)
			(layer "F.Fab")
		)
		(fp_line
			(start -0.67945 0.3048)
			(end -0.67945 -0.305054)
			(stroke
				(width 0.1)
				(type default)
			)
			(layer "F.Fab")
		)
		(fp_line
			(start -0.12065 -0.305054)
			(end -0.12065 -0.2794)
			(stroke
				(width 0.1)
				(type default)
			)
			(layer "F.Fab")
		)
		(fp_line
			(start -0.12065 -0.2794)
			(end 0.12065 -0.2794)
			(stroke
				(width 0.1)
				(type default)
			)
			(layer "F.Fab")
		)
		(fp_line
			(start -0.12065 0.2794)
			(end -0.12065 0.3048)
			(stroke
				(width 0.1)
				(type default)
			)
			(layer "F.Fab")
		)
		(fp_line
			(start -0.12065 0.3048)
			(end -0.67945 0.3048)
			(stroke
				(width 0.1)
				(type default)
			)
			(layer "F.Fab")
		)
		(fp_line
			(start 0.120396 0.2794)
			(end -0.12065 0.2794)
			(stroke
				(width 0.1)
				(type default)
			)
			(layer "F.Fab")
		)
		(fp_line
			(start 0.120396 0.3048)
			(end 0.120396 0.2794)
			(stroke
				(width 0.1)
				(type default)
			)
			(layer "F.Fab")
		)
		(fp_line
			(start 0.12065 -0.3048)
			(end 0.67945 -0.3048)
			(stroke
				(width 0.1)
				(type default)
			)
			(layer "F.Fab")
		)
		(fp_line
			(start 0.12065 -0.2794)
			(end 0.12065 -0.3048)
			(stroke
				(width 0.1)
				(type default)
			)
			(layer "F.Fab")
		)
		(fp_line
			(start 0.67945 -0.3048)
			(end 0.67945 0.3048)
			(stroke
				(width 0.1)
				(type default)
			)
			(layer "F.Fab")
		)
		(fp_line
			(start 0.67945 0.3048)
			(end 0.120396 0.3048)
			(stroke
				(width 0.1)
				(type default)
			)
			(layer "F.Fab")
		)
		(pad "1" smd circle
			(at -0.40005 0)
			(size 0 0)
			(layers "F.Cu" "F.Mask" "F.Paste")
			(net "P1V8_RETIMER_CPU0_EN")
		)
		(pad "2" smd circle
			(at 0.40005 0)
			(size 0 0)
			(layers "F.Cu" "F.Mask" "F.Paste")
			(net "P1V8_RETIMER_CPU0_R_EN")
		)
	)
)
